# BASEBOARD_FAB2 (Tioga Pass) — schematic netlist excerpt (pin names and nets, part order shuffled) for the footprints in the layout excerpt that follows; sources: Cadence DE-HDL packaged netlist, KiCad conversion of Wiwynn_Tioga_Pass_MB.brd

R9W31  21K5R2F-GP  1%  pkg RCL_GP  page 239 : \1\ = P2V5_AUX_BMC ; \2\ = VR_P2V5_BMC_STBY_FB
C4E14  SC22U16V5MX-4-GP  20%  pkg SMD-BCG5  page 214 : \1\ = VR_FET_SW_P12V_STBY_PVCCIN_CPU0 ; \2\ = GND
R1D55  RES  68.1K 1% EMPTY  pkg 0402  page 208 : A = VR_PVCCIN_CPU1_PH3_OCSET ; B = GND

(kicad_pcb
	(version 20260206)
	(generator "pcbnew")
	(generator_version "10.0")
	(general
		(thickness 1.6)
		(legacy_teardrops no)
	)
	(paper "A4")
	(title_block
		(title "Wiwynn_Tioga_Pass_MB.brd")
		(comment 1 "Tioga Pass / footprints 1239-1241 of 4770")
	)
	(layers
		(0 "F.Cu" signal "TOP")
		(4 "In1.Cu" signal "L2GND")
		(6 "In2.Cu" signal "L3")
		(8 "In3.Cu" signal "L4GND")
		(10 "In4.Cu" signal "L5")
		(12 "In5.Cu" signal "L6GND")
		(14 "In6.Cu" signal "L7VCC")
		(16 "In7.Cu" signal "L8VCC")
		(18 "In8.Cu" signal "L9GND")
		(20 "In9.Cu" signal "L10")
		(22 "In10.Cu" signal "L11GND")
		(24 "In11.Cu" signal "L12")
		(26 "In12.Cu" signal "L13GND")
		(2 "B.Cu" signal "BOTTOM")
		(9 "F.Adhes" user "F.Adhesive")
		(11 "B.Adhes" user "B.Adhesive")
		(13 "F.Paste" user "Package Geometry/Pastemask Top")
		(15 "B.Paste" user "Package Geometry/Pastemask Bottom")
		(5 "F.SilkS" user "Ref Des/Silkscreen Top")
		(7 "B.SilkS" user "Ref Des/Silkscreen Bottom")
		(1 "F.Mask" user "Board Geometry/Soldermask Top")
		(3 "B.Mask" user "Board Geometry/Soldermask Bottom")
		(17 "Dwgs.User" user "User.Drawings")
		(19 "Cmts.User" user "User.Comments")
		(21 "Eco1.User" user "User.Eco1")
		(23 "Eco2.User" user "User.Eco2")
		(25 "Edge.Cuts" user "Board Geometry/Outline")
		(27 "Margin" user)
		(31 "F.CrtYd" user "Package Geometry/Place Bound Top")
		(29 "B.CrtYd" user "Package Geometry/Place Bound Bottom")
		(35 "F.Fab" user "Ref Des/Assembly Top")
		(33 "B.Fab" user "Ref Des/Assembly Bottom")
	)
	(footprint ""
		(layer "F.Cu")
		(at 183.795416 -59.238896 180)
		(property "Reference" "C4E14"
			(at 0 0 180)
			(layer "F.SilkS")
			(hide yes)
			(effects
				(font
					(size 1.27 1.27)
				)
			)
		)
		(property "Value" "*"
			(at -0.0762 -6.2357 180)
			(unlocked yes)
			(layer "F.Fab")
			(hide yes)
			(effects
				(font
					(size 1.27 1.016)
					(thickness 0.1524)
				)
			)
		)
		(property "Device Type" "SC22U16V5MX-4-GP_SMD-BCG5-SC22A"
			(at -0.0762 -8.2677 180)
			(unlocked yes)
			(layer "F.Fab")
			(hide yes)
			(effects
				(font
					(size 1.27 1.016)
					(thickness 0.1524)
				)
			)
		)
		(duplicate_pad_numbers_are_jumpers no)
		(fp_line
			(start 0.635 0)
			(end -0.635 0)
			(stroke
				(width 0.508)
				(type default)
			)
			(layer "F.SilkS")
		)
		(fp_rect
			(start -0.9652 1.778)
			(end 0.9652 -1.778)
			(stroke
				(width 0)
				(type default)
			)
			(fill no)
			(layer "F.CrtYd")
		)
		(fp_poly
			(pts
				(xy -0.9652 -1.778) (xy 0.9652 -1.778) (xy 0.9652 1.778) (xy -0.9652 1.778)
			)
			(stroke
				(width 0)
				(type default)
			)
			(fill no)
			(layer "F.Fab")
		)
		(pad "1" smd rect
			(at 0 -0.9652 180)
			(size 1.397 1.143)
			(layers "F.Cu" "F.Mask" "F.Paste")
			(net "VR_FET_SW_P12V_STBY_PVCCIN_CPU0")
		)
		(pad "2" smd rect
			(at 0 0.9652 180)
			(size 1.397 1.143)
			(layers "F.Cu" "F.Mask" "F.Paste")
			(net "GND")
		)
	)
	(footprint ""
		(layer "F.Cu")
		(at 29.036518 -72.03313 -90)
		(property "Reference" "R1D55"
			(at 0 0 270)
			(layer "F.SilkS")
			(hide yes)
			(effects
				(font
					(size 1.27 1.27)
				)
			)
		)
		(property "Value" ""
			(at 0 0 270)
			(layer "F.Fab")
			(effects
				(font
					(size 1.27 1.27)
				)
			)
		)
		(duplicate_pad_numbers_are_jumpers no)
		(fp_poly
			(pts
				(xy -0.2794 -0.1016) (xy 0.2794 -0.1016) (xy 0.2794 0.9906) (xy -0.2794 0.9906)
			)
			(stroke
				(width 0)
				(type default)
			)
			(fill no)
			(layer "F.CrtYd")
		)
		(fp_line
			(start -0.2794 0.9906)
			(end 0.2794 0.9906)
			(stroke
				(width 0.1)
				(type default)
			)
			(layer "F.Fab")
		)
		(fp_line
			(start 0.2794 0.9906)
			(end 0.2794 -0.1016)
			(stroke
				(width 0.1)
				(type default)
			)
			(layer "F.Fab")
		)
		(fp_line
			(start -0.2794 -0.1016)
			(end -0.2794 0.9906)
			(stroke
				(width 0.1)
				(type default)
			)
			(layer "F.Fab")
		)
		(fp_line
			(start 0.2794 -0.1016)
			(end -0.2794 -0.1016)
			(stroke
				(width 0.1)
				(type default)
			)
			(layer "F.Fab")
		)
		(pad "1" smd rect
			(at 0 0 270)
			(size 0.508 0.508)
			(layers "F.Cu" "F.Mask" "F.Paste")
			(net "VR_PVCCIN_CPU1_PH3_OCSET")
		)
		(pad "2" smd rect
			(at 0 0.889 270)
			(size 0.508 0.508)
			(layers "F.Cu" "F.Mask" "F.Paste")
			(net "GND")
		)
		(zone
			(layer "F.Cu")
			(hatch none 0.5)
			(connect_pads
				(clearance 0)
			)
			(min_thickness 0.25)
			(keepout
				(tracks not_allowed)
				(vias allowed)
				(pads allowed)
				(copperpour not_allowed)
				(footprints allowed)
			)
			(placement
				(enabled no)
				(sheetname "")
			)
			(fill
				(thermal_gap 0.5)
				(thermal_bridge_width 0.5)
				(island_removal_mode 0)
			)
			(polygon
				(pts
					(xy 28.401518 -72.28713) (xy 28.401518 -71.77913) (xy 28.782518 -71.77913) (xy 28.782518 -72.28713)
				)
			)
		)
		(zone
			(layer "F.Cu")
			(hatch none 0.5)
			(connect_pads
				(clearance 0)
			)
			(min_thickness 0.25)
			(keepout
				(tracks allowed)
				(vias not_allowed)
				(pads allowed)
				(copperpour not_allowed)
				(footprints allowed)
			)
			(placement
				(enabled no)
				(sheetname "")
			)
			(fill
				(thermal_gap 0.5)
				(thermal_bridge_width 0.5)
				(island_removal_mode 0)
			)
			(polygon
				(pts
					(xy 28.782518 -72.28713) (xy 28.782518 -71.77913) (xy 28.401518 -71.77913) (xy 28.401518 -72.28713)
				)
			)
		)
	)
	(footprint ""
		(layer "F.Cu")
		(at 451.3326 -22.4282)
		(property "Reference" "R9W31"
			(at 0 0 0)
			(layer "F.SilkS")
			(hide yes)
			(effects
				(font
					(size 1.27 1.27)
				)
			)
		)
		(property "Value" "*"
			(at 0.064008 -4.108196 0)
			(unlocked yes)
			(layer "F.Fab")
			(hide yes)
			(effects
				(font
					(size 1.27 1.016)
					(thickness 0.1524)
				)
			)
		)
		(property "Device Type" "21K5R2F-GP_RCL_GP-21K5R2F-GP,6A"
			(at 0.064008 -5.632196 0)
			(unlocked yes)
			(layer "F.Fab")
			(hide yes)
			(effects
				(font
					(size 1.27 1.016)
					(thickness 0.1524)
				)
			)
		)
		(duplicate_pad_numbers_are_jumpers no)
		(fp_line
			(start -0.508 -0.9398)
			(end -0.508 0.9398)
			(stroke
				(width 0.1524)
				(type default)
			)
			(layer "F.SilkS")
		)
		(fp_line
			(start 0.508 -0.9398)
			(end -0.508 -0.9398)
			(stroke
				(width 0.1524)
				(type default)
			)
			(layer "F.SilkS")
		)
		(fp_rect
			(start -0.508 0.9398)
			(end 0.508 -0.9398)
			(stroke
				(width 0)
				(type default)
			)
			(fill no)
			(layer "F.CrtYd")
		)
		(fp_rect
			(start -0.508 0.9398)
			(end 0.508 -0.9398)
			(stroke
				(width 0)
				(type default)
			)
			(fill no)
			(layer "F.Fab")
		)
		(pad "1" smd custom
			(at 0 -0.4445)
			(size 0.1397 0.1397)
			(layers "F.Cu" "F.Mask" "F.Paste")
			(net "P2V5_AUX_BMC")
			(options
				(clearance outline)
				(anchor circle)
			)
			(primitives
				(gr_poly
					(pts
						(arc
							(start -0.1778 -0.2794)
							(mid -0.249642 -0.249642)
							(end -0.2794 -0.1778)
						)
						(arc
							(start -0.2794 0.1778)
							(mid -0.249642 0.249642)
							(end -0.1778 0.2794)
						)
						(arc
							(start 0.1778 0.2794)
							(mid 0.249642 0.249642)
							(end 0.2794 0.1778)
						)
						(arc
							(start 0.2794 -0.1778)
							(mid 0.249642 -0.249642)
							(end 0.1778 -0.2794)
						)
					)
					(width 0)
					(fill yes)
				)
			)
		)
		(pad "2" smd custom
			(at 0 0.4445)
			(size 0.1397 0.1397)
			(layers "F.Cu" "F.Mask" "F.Paste")
			(net "VR_P2V5_BMC_STBY_FB")
			(options
				(clearance outline)
				(anchor circle)
			)
			(primitives
				(gr_poly
					(pts
						(arc
							(start -0.1778 -0.2794)
							(mid -0.249642 -0.249642)
							(end -0.2794 -0.1778)
						)
						(arc
							(start -0.2794 0.1778)
							(mid -0.249642 0.249642)
							(end -0.1778 0.2794)
						)
						(arc
							(start 0.1778 0.2794)
							(mid 0.249642 0.249642)
							(end 0.2794 0.1778)
						)
						(arc
							(start 0.2794 -0.1778)
							(mid 0.249642 -0.249642)
							(end 0.1778 -0.2794)
						)
					)
					(width 0)
					(fill yes)
				)
			)
		)
	)
)
